# S9S_MB_2U (Grand Teton) — schematic netlist excerpt (pin names and nets, part order shuffled) for the footprints in the layout excerpt that follows; sources: Cadence DE-HDL packaged netlist, KiCad conversion of 03242023_DA0F0TMBIJ0_F0T_Motherboard_J_brd_V01_OCP.brd

C1819  Q_CAP  0.1UF 25V 10% X7R  pkg 0402  page 164 : A = P3V3_OCP_V3_2 ; B = GND
R3027  Q_RES  1K 1% CHIP  pkg 0402LF  page 134 : A = JTAG_BMC_CPU_TCK ; B = GND

(kicad_pcb
	(version 20260206)
	(generator "pcbnew")
	(generator_version "10.0")
	(general
		(thickness 1.6)
		(legacy_teardrops no)
	)
	(paper "A4")
	(title_block
		(title "03242023_DA0F0TMBIJ0_F0T_Motherboard_J_brd_V01_OCP.brd")
		(comment 1 "Grand Teton / footprints 4066-4067 of 6105")
	)
	(layers
		(0 "F.Cu" signal "TOP")
		(4 "In1.Cu" signal "GND")
		(6 "In2.Cu" signal "IN1")
		(8 "In3.Cu" signal "GND1")
		(10 "In4.Cu" signal "IN2")
		(12 "In5.Cu" signal "GND2")
		(14 "In6.Cu" signal "IN3")
		(16 "In7.Cu" signal "GND3")
		(18 "In8.Cu" signal "VCC")
		(20 "In9.Cu" signal "VCC1")
		(22 "In10.Cu" signal "GND4")
		(24 "In11.Cu" signal "IN4")
		(26 "In12.Cu" signal "GND5")
		(28 "In13.Cu" signal "IN5")
		(30 "In14.Cu" signal "GND6")
		(32 "In15.Cu" signal "IN6")
		(34 "In16.Cu" signal "GND7")
		(2 "B.Cu" signal "BOTTOM")
		(9 "F.Adhes" user "F.Adhesive")
		(11 "B.Adhes" user "B.Adhesive")
		(13 "F.Paste" user "Package Geometry/Pastemask Top")
		(15 "B.Paste" user "Package Geometry/Pastemask Bottom")
		(5 "F.SilkS" user "Ref Des/Silkscreen Top")
		(7 "B.SilkS" user "Ref Des/Silkscreen Bottom")
		(1 "F.Mask" user "Board Geometry/Soldermask Top")
		(3 "B.Mask" user "Board Geometry/Soldermask Bottom")
		(17 "Dwgs.User" user "User.Drawings")
		(19 "Cmts.User" user "User.Comments")
		(21 "Eco1.User" user "User.Eco1")
		(23 "Eco2.User" user "User.Eco2")
		(25 "Edge.Cuts" user "Board Geometry/Outline")
		(27 "Margin" user)
		(31 "F.CrtYd" user "Package Geometry/Place Bound Top")
		(29 "B.CrtYd" user "Package Geometry/Place Bound Bottom")
		(35 "F.Fab" user "Ref Des/Assembly Top")
		(33 "B.Fab" user "Ref Des/Assembly Bottom")
	)
	(footprint ""
		(layer "F.Cu")
		(at 96.57588 -56.225948 180)
		(property "Reference" "R3027"
			(at 0 0 180)
			(layer "F.SilkS")
			(hide yes)
			(effects
				(font
					(size 1.27 1.27)
				)
			)
		)
		(property "Value" ""
			(at 0 0 180)
			(layer "F.Fab")
			(effects
				(font
					(size 1.27 1.27)
				)
			)
		)
		(duplicate_pad_numbers_are_jumpers no)
		(fp_line
			(start 0.7874 0.4064)
			(end -0.7874 0.4064)
			(stroke
				(width 0.1524)
				(type default)
			)
			(layer "F.SilkS")
		)
		(fp_line
			(start 0.7874 -0.4064)
			(end 0.7874 0.4064)
			(stroke
				(width 0.1524)
				(type default)
			)
			(layer "F.SilkS")
		)
		(fp_line
			(start -0.7874 0.4064)
			(end -0.7874 -0.4064)
			(stroke
				(width 0.1524)
				(type default)
			)
			(layer "F.SilkS")
		)
		(fp_line
			(start -0.7874 -0.4064)
			(end 0.7874 -0.4064)
			(stroke
				(width 0.1524)
				(type default)
			)
			(layer "F.SilkS")
		)
		(fp_line
			(start 0.67945 0.3048)
			(end 0.120396 0.3048)
			(stroke
				(width 0.1)
				(type default)
			)
			(layer "F.Fab")
		)
		(fp_line
			(start 0.67945 -0.3048)
			(end 0.67945 0.3048)
			(stroke
				(width 0.1)
				(type default)
			)
			(layer "F.Fab")
		)
		(fp_line
			(start 0.12065 -0.2794)
			(end 0.12065 -0.3048)
			(stroke
				(width 0.1)
				(type default)
			)
			(layer "F.Fab")
		)
		(fp_line
			(start 0.12065 -0.3048)
			(end 0.67945 -0.3048)
			(stroke
				(width 0.1)
				(type default)
			)
			(layer "F.Fab")
		)
		(fp_line
			(start 0.120396 0.3048)
			(end 0.120396 0.2794)
			(stroke
				(width 0.1)
				(type default)
			)
			(layer "F.Fab")
		)
		(fp_line
			(start 0.120396 0.2794)
			(end -0.12065 0.2794)
			(stroke
				(width 0.1)
				(type default)
			)
			(layer "F.Fab")
		)
		(fp_line
			(start -0.12065 0.3048)
			(end -0.67945 0.3048)
			(stroke
				(width 0.1)
				(type default)
			)
			(layer "F.Fab")
		)
		(fp_line
			(start -0.12065 0.2794)
			(end -0.12065 0.3048)
			(stroke
				(width 0.1)
				(type default)
			)
			(layer "F.Fab")
		)
		(fp_line
			(start -0.12065 -0.2794)
			(end 0.12065 -0.2794)
			(stroke
				(width 0.1)
				(type default)
			)
			(layer "F.Fab")
		)
		(fp_line
			(start -0.12065 -0.305054)
			(end -0.12065 -0.2794)
			(stroke
				(width 0.1)
				(type default)
			)
			(layer "F.Fab")
		)
		(fp_line
			(start -0.67945 0.3048)
			(end -0.67945 -0.305054)
			(stroke
				(width 0.1)
				(type default)
			)
			(layer "F.Fab")
		)
		(fp_line
			(start -0.67945 -0.305054)
			(end -0.12065 -0.305054)
			(stroke
				(width 0.1)
				(type default)
			)
			(layer "F.Fab")
		)
		(pad "1" smd circle
			(at -0.40005 0 180)
			(size 0 0)
			(layers "F.Cu" "F.Mask" "F.Paste")
			(net "JTAG_BMC_CPU_TCK")
		)
		(pad "2" smd circle
			(at 0.40005 0 180)
			(size 0 0)
			(layers "F.Cu" "F.Mask" "F.Paste")
			(net "GND")
		)
	)
	(footprint ""
		(layer "F.Cu")
		(at 77.8764 -37.262308 180)
		(property "Reference" "C1819"
			(at 0 0 180)
			(layer "F.SilkS")
			(hide yes)
			(effects
				(font
					(size 1.27 1.27)
				)
			)
		)
		(property "Value" ""
			(at 0 0 180)
			(layer "F.Fab")
			(effects
				(font
					(size 1.27 1.27)
				)
			)
		)
		(duplicate_pad_numbers_are_jumpers no)
		(fp_line
			(start 0.7874 0.4064)
			(end -0.7874 0.4064)
			(stroke
				(width 0.1524)
				(type default)
			)
			(layer "F.SilkS")
		)
		(fp_line
			(start 0.7874 -0.4064)
			(end 0.7874 0.4064)
			(stroke
				(width 0.1524)
				(type default)
			)
			(layer "F.SilkS")
		)
		(fp_line
			(start -0.7874 0.4064)
			(end -0.7874 -0.4064)
			(stroke
				(width 0.1524)
				(type default)
			)
			(layer "F.SilkS")
		)
		(fp_line
			(start -0.7874 -0.4064)
			(end 0.7874 -0.4064)
			(stroke
				(width 0.1524)
				(type default)
			)
			(layer "F.SilkS")
		)
		(fp_line
			(start 0.67945 0.3048)
			(end 0.120396 0.3048)
			(stroke
				(width 0.1)
				(type default)
			)
			(layer "F.Fab")
		)
		(fp_line
			(start 0.67945 -0.3048)
			(end 0.67945 0.3048)
			(stroke
				(width 0.1)
				(type default)
			)
			(layer "F.Fab")
		)
		(fp_line
			(start 0.12065 -0.2794)
			(end 0.12065 -0.3048)
			(stroke
				(width 0.1)
				(type default)
			)
			(layer "F.Fab")
		)
		(fp_line
			(start 0.12065 -0.3048)
			(end 0.67945 -0.3048)
			(stroke
				(width 0.1)
				(type default)
			)
			(layer "F.Fab")
		)
		(fp_line
			(start 0.120396 0.3048)
			(end 0.120396 0.2794)
			(stroke
				(width 0.1)
				(type default)
			)
			(layer "F.Fab")
		)
		(fp_line
			(start 0.120396 0.2794)
			(end -0.12065 0.2794)
			(stroke
				(width 0.1)
				(type default)
			)
			(layer "F.Fab")
		)
		(fp_line
			(start -0.12065 0.3048)
			(end -0.67945 0.3048)
			(stroke
				(width 0.1)
				(type default)
			)
			(layer "F.Fab")
		)
		(fp_line
			(start -0.12065 0.2794)
			(end -0.12065 0.3048)
			(stroke
				(width 0.1)
				(type default)
			)
			(layer "F.Fab")
		)
		(fp_line
			(start -0.12065 -0.2794)
			(end 0.12065 -0.2794)
			(stroke
				(width 0.1)
				(type default)
			)
			(layer "F.Fab")
		)
		(fp_line
			(start -0.12065 -0.305054)
			(end -0.12065 -0.2794)
			(stroke
				(width 0.1)
				(type default)
			)
			(layer "F.Fab")
		)
		(fp_line
			(start -0.67945 0.3048)
			(end -0.67945 -0.305054)
			(stroke
				(width 0.1)
				(type default)
			)
			(layer "F.Fab")
		)
		(fp_line
			(start -0.67945 -0.305054)
			(end -0.12065 -0.305054)
			(stroke
				(width 0.1)
				(type default)
			)
			(layer "F.Fab")
		)
		(pad "1" smd circle
			(at -0.40005 0 180)
			(size 0 0)
			(layers "F.Cu" "F.Mask" "F.Paste")
			(net "P3V3_OCP_V3_2")
		)
		(pad "2" smd circle
			(at 0.40005 0 180)
			(size 0 0)
			(layers "F.Cu" "F.Mask" "F.Paste")
			(net "GND")
		)
	)
)
